(kicad_pcb
	(version 20260206)
	(generator "pcbnew")
	(generator_version "10.0")
	(general
		(thickness 1.6)
		(legacy_teardrops no)
	)
	(paper "A4")
	(title_block
		(title "04192023_DAF0TMB3IC0_F0TG_MB_C_brd_V02_OCP.brd")
		(comment 1 "Grand Teton / footprint 2783 of 8354 (U26), pads 4225-4341 of 6102")
	)
	(layers
		(0 "F.Cu" signal "TOP")
		(4 "In1.Cu" signal "GND")
		(6 "In2.Cu" signal "IN1")
		(8 "In3.Cu" signal "GND1")
		(10 "In4.Cu" signal "IN2")
		(12 "In5.Cu" signal "GND2")
		(14 "In6.Cu" signal "IN3")
		(16 "In7.Cu" signal "GND3")
		(18 "In8.Cu" signal "VCC")
		(20 "In9.Cu" signal "VCC1")
		(22 "In10.Cu" signal "GND4")
		(24 "In11.Cu" signal "IN4")
		(26 "In12.Cu" signal "GND5")
		(28 "In13.Cu" signal "IN5")
		(30 "In14.Cu" signal "GND6")
		(32 "In15.Cu" signal "IN6")
		(34 "In16.Cu" signal "GND7")
		(2 "B.Cu" signal "BOTTOM")
		(9 "F.Adhes" user "F.Adhesive")
		(11 "B.Adhes" user "B.Adhesive")
		(13 "F.Paste" user "Package Geometry/Pastemask Top")
		(15 "B.Paste" user "Package Geometry/Pastemask Bottom")
		(5 "F.SilkS" user "Ref Des/Silkscreen Top")
		(7 "B.SilkS" user "Ref Des/Silkscreen Bottom")
		(1 "F.Mask" user "Board Geometry/Soldermask Top")
		(3 "B.Mask" user "Board Geometry/Soldermask Bottom")
		(17 "Dwgs.User" user "User.Drawings")
		(19 "Cmts.User" user "User.Comments")
		(21 "Eco1.User" user "User.Eco1")
		(23 "Eco2.User" user "User.Eco2")
		(25 "Edge.Cuts" user "Board Geometry/Outline")
		(27 "Margin" user)
		(31 "F.CrtYd" user "Package Geometry/Place Bound Top")
		(29 "B.CrtYd" user "Package Geometry/Place Bound Bottom")
		(35 "F.Fab" user "Ref Des/Assembly Top")
		(33 "B.Fab" user "Ref Des/Assembly Bottom")
	)
	(footprint ""
		(layer "F.Cu")
		(at 111.927894 -258.880356 180)
		(property "Reference" "U26"
			(at -45.05579 -61.794136 0)
			(unlocked yes)
			(layer "F.SilkS")
			(effects
				(font
					(size 0.7874 0.5842)
					(thickness 0.1524)
				)
			)
		)
		(property "Value" ""
			(at 0 0 180)
			(layer "F.Fab")
			(effects
				(font
					(size 1.27 1.27)
				)
			)
		)
		(duplicate_pad_numbers_are_jumpers no)
		(pad "CY51" smd circle
			(at 12.07008 29.51988 180)
			(size 0.450088 0.450088)
			(layers "F.Cu" "F.Mask" "F.Paste")
			(net "GND")
		)
		(pad "CY52" smd circle
			(at 13.00988 29.51988 180)
			(size 0.450088 0.450088)
			(layers "F.Cu" "F.Mask" "F.Paste")
			(net "GND")
		)
		(pad "CY53" smd circle
			(at 13.949934 29.51988 180)
			(size 0.450088 0.450088)
			(layers "F.Cu" "F.Mask" "F.Paste")
			(net "GND")
		)
		(pad "CY54" smd circle
			(at 14.889988 29.51988 180)
			(size 0.450088 0.450088)
			(layers "F.Cu" "F.Mask" "F.Paste")
			(net "PVDDIO_P1")
		)
		(pad "CY55" smd circle
			(at 15.830042 29.51988 180)
			(size 0.450088 0.450088)
			(layers "F.Cu" "F.Mask" "F.Paste")
			(net "M_C_CPU1_SB_DQ<23>")
		)
		(pad "CY56" smd circle
			(at 16.770096 29.51988 180)
			(size 0.450088 0.450088)
			(layers "F.Cu" "F.Mask" "F.Paste")
			(net "M_C_CPU1_SB_DQ<24>")
		)
		(pad "CY57" smd circle
			(at 17.709896 29.51988 180)
			(size 0.450088 0.450088)
			(layers "F.Cu" "F.Mask" "F.Paste")
			(net "GND")
		)
		(pad "CY58" smd circle
			(at 18.64995 29.51988 180)
			(size 0.450088 0.450088)
			(layers "F.Cu" "F.Mask" "F.Paste")
			(net "M_D_CPU1_SB_DQ<23>")
		)
		(pad "CY59" smd circle
			(at 19.590004 29.51988 180)
			(size 0.450088 0.450088)
			(layers "F.Cu" "F.Mask" "F.Paste")
			(net "GND")
		)
		(pad "CY60" smd circle
			(at 20.530058 29.51988 180)
			(size 0.450088 0.450088)
			(layers "F.Cu" "F.Mask" "F.Paste")
			(net "M_D_CPU1_SB_DQ<24>")
		)
		(pad "CY61" smd circle
			(at 21.470112 29.51988 180)
			(size 0.450088 0.450088)
			(layers "F.Cu" "F.Mask" "F.Paste")
			(net "GND")
		)
		(pad "CY62" smd circle
			(at 22.409912 29.51988 180)
			(size 0.450088 0.450088)
			(layers "F.Cu" "F.Mask" "F.Paste")
			(net "M_B_CPU1_SB_DQ<23>")
		)
		(pad "CY63" smd circle
			(at 23.349966 29.51988 180)
			(size 0.450088 0.450088)
			(layers "F.Cu" "F.Mask" "F.Paste")
			(net "M_B_CPU1_SB_DQ<24>")
		)
		(pad "CY64" smd circle
			(at 24.29002 29.51988 180)
			(size 0.450088 0.450088)
			(layers "F.Cu" "F.Mask" "F.Paste")
			(net "GND")
		)
		(pad "CY65" smd circle
			(at 25.230074 29.51988 180)
			(size 0.450088 0.450088)
			(layers "F.Cu" "F.Mask" "F.Paste")
			(net "M_F_CPU1_SB_DQ<23>")
		)
		(pad "CY66" smd circle
			(at 26.170128 29.51988 180)
			(size 0.450088 0.450088)
			(layers "F.Cu" "F.Mask" "F.Paste")
			(net "GND")
		)
		(pad "CY67" smd circle
			(at 27.109928 29.51988 180)
			(size 0.450088 0.450088)
			(layers "F.Cu" "F.Mask" "F.Paste")
			(net "M_F_CPU1_SB_DQ<24>")
		)
		(pad "CY68" smd circle
			(at 28.049982 29.51988 180)
			(size 0.450088 0.450088)
			(layers "F.Cu" "F.Mask" "F.Paste")
			(net "GND")
		)
		(pad "CY69" smd circle
			(at 28.990036 29.51988 180)
			(size 0.450088 0.450088)
			(layers "F.Cu" "F.Mask" "F.Paste")
			(net "M_E_CPU1_SB_DQ<23>")
		)
		(pad "CY70" smd circle
			(at 29.93009 29.51988 180)
			(size 0.450088 0.450088)
			(layers "F.Cu" "F.Mask" "F.Paste")
			(net "M_E_CPU1_SB_DQ<24>")
		)
		(pad "CY71" smd circle
			(at 30.86989 29.51988 180)
			(size 0.450088 0.450088)
			(layers "F.Cu" "F.Mask" "F.Paste")
			(net "GND")
		)
		(pad "CY72" smd circle
			(at 31.809944 29.51988 180)
			(size 0.450088 0.450088)
			(layers "F.Cu" "F.Mask" "F.Paste")
			(net "M_A_CPU1_SB_DQ<23>")
		)
		(pad "CY73" smd circle
			(at 32.749998 29.51988 180)
			(size 0.450088 0.450088)
			(layers "F.Cu" "F.Mask" "F.Paste")
			(net "GND")
		)
		(pad "CY74" smd circle
			(at 33.690052 29.51988 180)
			(size 0.450088 0.450088)
			(layers "F.Cu" "F.Mask" "F.Paste")
			(net "M_A_CPU1_SB_DQ<24>")
		)
		(pad "D2" smd circle
			(at -33.690052 -34.379916 180)
			(size 0.450088 0.450088)
			(layers "F.Cu" "F.Mask" "F.Paste")
			(net "GND")
		)
		(pad "D3" smd circle
			(at -32.749998 -34.379916 180)
			(size 0.450088 0.450088)
			(layers "F.Cu" "F.Mask" "F.Paste")
			(net "GND")
		)
		(pad "D4" smd circle
			(at -31.809944 -34.379916 180)
			(size 0.450088 0.450088)
			(layers "F.Cu" "F.Mask" "F.Paste")
			(net "Net_2157")
		)
		(pad "D5" smd circle
			(at -30.86989 -34.379916 180)
			(size 0.450088 0.450088)
			(layers "F.Cu" "F.Mask" "F.Paste")
			(net "GND")
		)
		(pad "D6" smd circle
			(at -29.93009 -34.379916 180)
			(size 0.450088 0.450088)
			(layers "F.Cu" "F.Mask" "F.Paste")
			(net "GND")
		)
		(pad "D7" smd circle
			(at -28.990036 -34.379916 180)
			(size 0.450088 0.450088)
			(layers "F.Cu" "F.Mask" "F.Paste")
			(net "TP_CPU1_TEST47_IOD1")
		)
		(pad "D8" smd circle
			(at -28.049982 -34.379916 180)
			(size 0.450088 0.450088)
			(layers "F.Cu" "F.Mask" "F.Paste")
			(net "Net_2162")
		)
		(pad "D9" smd circle
			(at -27.109928 -34.379916 180)
			(size 0.450088 0.450088)
			(layers "F.Cu" "F.Mask" "F.Paste")
			(net "GND")
		)
		(pad "D10" smd circle
			(at -26.170128 -34.379916 180)
			(size 0.450088 0.450088)
			(layers "F.Cu" "F.Mask" "F.Paste")
			(net "GND")
		)
		(pad "D11" smd circle
			(at -25.230074 -34.379916 180)
			(size 0.450088 0.450088)
			(layers "F.Cu" "F.Mask" "F.Paste")
			(net "Net_2153")
		)
		(pad "D12" smd circle
			(at -24.29002 -34.379916 180)
			(size 0.450088 0.450088)
			(layers "F.Cu" "F.Mask" "F.Paste")
			(net "GND")
		)
		(pad "D13" smd circle
			(at -23.349966 -34.379916 180)
			(size 0.450088 0.450088)
			(layers "F.Cu" "F.Mask" "F.Paste")
			(net "GND")
		)
		(pad "D14" smd circle
			(at -22.409912 -34.379916 180)
			(size 0.450088 0.450088)
			(layers "F.Cu" "F.Mask" "F.Paste")
			(net "SMB_CPU1_SEC_SDA")
		)
		(pad "D15" smd circle
			(at -21.470112 -34.379916 180)
			(size 0.450088 0.450088)
			(layers "F.Cu" "F.Mask" "F.Paste")
			(net "Net_2100")
		)
		(pad "D16" smd circle
			(at -20.530058 -34.379916 180)
			(size 0.450088 0.450088)
			(layers "F.Cu" "F.Mask" "F.Paste")
			(net "GND")
		)
		(pad "D17" smd circle
			(at -19.590004 -34.379916 180)
			(size 0.450088 0.450088)
			(layers "F.Cu" "F.Mask" "F.Paste")
			(net "GND")
		)
		(pad "D18" smd circle
			(at -18.64995 -34.379916 180)
			(size 0.450088 0.450088)
			(layers "F.Cu" "F.Mask" "F.Paste")
			(net "RST_CPU1_PERST0_N")
		)
		(pad "D19" smd circle
			(at -17.709896 -34.379916 180)
			(size 0.450088 0.450088)
			(layers "F.Cu" "F.Mask" "F.Paste")
			(net "GND")
		)
		(pad "D20" smd circle
			(at -16.770096 -34.379916 180)
			(size 0.450088 0.450088)
			(layers "F.Cu" "F.Mask" "F.Paste")
			(net "GND")
		)
		(pad "D21" smd circle
			(at -15.830042 -34.379916 180)
			(size 0.450088 0.450088)
			(layers "F.Cu" "F.Mask" "F.Paste")
			(net "GND")
		)
		(pad "D22" smd circle
			(at -14.889988 -34.379916 180)
			(size 0.450088 0.450088)
			(layers "F.Cu" "F.Mask" "F.Paste")
			(net "Net_2154")
		)
		(pad "D23" smd circle
			(at -13.949934 -34.379916 180)
			(size 0.450088 0.450088)
			(layers "F.Cu" "F.Mask" "F.Paste")
			(net "Net_2176")
		)
		(pad "D24" smd circle
			(at -13.00988 -34.379916 180)
			(size 0.450088 0.450088)
			(layers "F.Cu" "F.Mask" "F.Paste")
			(net "GND")
		)
		(pad "D25" smd circle
			(at -12.07008 -34.379916 180)
			(size 0.450088 0.450088)
			(layers "F.Cu" "F.Mask" "F.Paste")
			(net "GND")
		)
		(pad "D26" smd circle
			(at -11.130026 -34.379916 180)
			(size 0.450088 0.450088)
			(layers "F.Cu" "F.Mask" "F.Paste")
			(net "GND")
		)
		(pad "D27" smd circle
			(at -10.189972 -34.379916 180)
			(size 0.450088 0.450088)
			(layers "F.Cu" "F.Mask" "F.Paste")
			(net "GND")
		)
		(pad "D28" smd circle
			(at -9.249918 -34.379916 180)
			(size 0.450088 0.450088)
			(layers "F.Cu" "F.Mask" "F.Paste")
			(net "GND")
		)
		(pad "D29" smd circle
			(at -8.310118 -34.379916 180)
			(size 0.450088 0.450088)
			(layers "F.Cu" "F.Mask" "F.Paste")
			(net "GND")
		)
		(pad "D30" smd circle
			(at -7.370064 -34.379916 180)
			(size 0.450088 0.450088)
			(layers "F.Cu" "F.Mask" "F.Paste")
			(net "GND")
		)
		(pad "D31" smd circle
			(at -6.43001 -34.379916 180)
			(size 0.450088 0.450088)
			(layers "F.Cu" "F.Mask" "F.Paste")
			(net "GND")
		)
		(pad "D32" smd circle
			(at -5.489956 -34.379916 180)
			(size 0.450088 0.450088)
			(layers "F.Cu" "F.Mask" "F.Paste")
			(net "NC_CPU1_AZ_SYNC")
		)
		(pad "D33" smd circle
			(at -4.549902 -34.379916 180)
			(size 0.450088 0.450088)
			(layers "F.Cu" "F.Mask" "F.Paste")
			(net "NC_CPU1_AZ_SDIN1")
		)
		(pad "D34" smd circle
			(at -3.610102 -34.379916 180)
			(size 0.450088 0.450088)
			(layers "F.Cu" "F.Mask" "F.Paste")
			(net "Net_2155")
		)
		(pad "D35" smd circle
			(at -2.670048 -34.379916 180)
			(size 0.450088 0.450088)
			(layers "F.Cu" "F.Mask" "F.Paste")
			(net "GND")
		)
		(pad "D36" smd circle
			(at -1.729994 -34.379916 180)
			(size 0.450088 0.450088)
			(layers "F.Cu" "F.Mask" "F.Paste")
			(net "Net_2156")
		)
		(pad "D37" smd circle
			(at -0.78994 -34.379916 180)
			(size 0.450088 0.450088)
			(layers "F.Cu" "F.Mask" "F.Paste")
			(net "GND")
		)
		(pad "D39" smd circle
			(at 1.089914 -34.379916 180)
			(size 0.450088 0.450088)
			(layers "F.Cu" "F.Mask" "F.Paste")
			(net "GND")
		)
		(pad "D40" smd circle
			(at 2.029968 -34.379916 180)
			(size 0.450088 0.450088)
			(layers "F.Cu" "F.Mask" "F.Paste")
			(net "GND")
		)
		(pad "D41" smd circle
			(at 2.970022 -34.379916 180)
			(size 0.450088 0.450088)
			(layers "F.Cu" "F.Mask" "F.Paste")
			(net "GND")
		)
		(pad "D42" smd circle
			(at 3.910076 -34.379916 180)
			(size 0.450088 0.450088)
			(layers "F.Cu" "F.Mask" "F.Paste")
			(net "GND")
		)
		(pad "D43" smd circle
			(at 4.849876 -34.379916 180)
			(size 0.450088 0.450088)
			(layers "F.Cu" "F.Mask" "F.Paste")
			(net "GND")
		)
		(pad "D44" smd circle
			(at 5.78993 -34.379916 180)
			(size 0.450088 0.450088)
			(layers "F.Cu" "F.Mask" "F.Paste")
			(net "GND")
		)
		(pad "D45" smd circle
			(at 6.729984 -34.379916 180)
			(size 0.450088 0.450088)
			(layers "F.Cu" "F.Mask" "F.Paste")
			(net "GND")
		)
		(pad "D46" smd circle
			(at 7.670038 -34.379916 180)
			(size 0.450088 0.450088)
			(layers "F.Cu" "F.Mask" "F.Paste")
			(net "GND")
		)
		(pad "D47" smd circle
			(at 8.610092 -34.379916 180)
			(size 0.450088 0.450088)
			(layers "F.Cu" "F.Mask" "F.Paste")
			(net "GND")
		)
		(pad "D48" smd circle
			(at 9.549892 -34.379916 180)
			(size 0.450088 0.450088)
			(layers "F.Cu" "F.Mask" "F.Paste")
			(net "GND")
		)
		(pad "D49" smd circle
			(at 10.489946 -34.379916 180)
			(size 0.450088 0.450088)
			(layers "F.Cu" "F.Mask" "F.Paste")
			(net "GND")
		)
		(pad "D50" smd circle
			(at 11.43 -34.379916 180)
			(size 0.450088 0.450088)
			(layers "F.Cu" "F.Mask" "F.Paste")
			(net "GND")
		)
		(pad "D51" smd circle
			(at 12.370054 -34.379916 180)
			(size 0.450088 0.450088)
			(layers "F.Cu" "F.Mask" "F.Paste")
			(net "GND")
		)
		(pad "D52" smd circle
			(at 13.310108 -34.379916 180)
			(size 0.450088 0.450088)
			(layers "F.Cu" "F.Mask" "F.Paste")
			(net "GND")
		)
		(pad "D53" smd circle
			(at 14.249908 -34.379916 180)
			(size 0.450088 0.450088)
			(layers "F.Cu" "F.Mask" "F.Paste")
			(net "GND")
		)
		(pad "D54" smd circle
			(at 15.189962 -34.379916 180)
			(size 0.450088 0.450088)
			(layers "F.Cu" "F.Mask" "F.Paste")
			(net "GND")
		)
		(pad "D55" smd circle
			(at 16.130016 -34.379916 180)
			(size 0.450088 0.450088)
			(layers "F.Cu" "F.Mask" "F.Paste")
			(net "PVDDCR_CPU0_P1")
		)
		(pad "D56" smd circle
			(at 17.07007 -34.379916 180)
			(size 0.450088 0.450088)
			(layers "F.Cu" "F.Mask" "F.Paste")
			(net "PVDDCR_CPU0_P1")
		)
		(pad "D57" smd circle
			(at 18.010124 -34.379916 180)
			(size 0.450088 0.450088)
			(layers "F.Cu" "F.Mask" "F.Paste")
			(net "GND")
		)
		(pad "D58" smd circle
			(at 18.949924 -34.379916 180)
			(size 0.450088 0.450088)
			(layers "F.Cu" "F.Mask" "F.Paste")
			(net "Net_2158")
		)
		(pad "D59" smd circle
			(at 19.889978 -34.379916 180)
			(size 0.450088 0.450088)
			(layers "F.Cu" "F.Mask" "F.Paste")
			(net "GND")
		)
		(pad "D60" smd circle
			(at 20.830032 -34.379916 180)
			(size 0.450088 0.450088)
			(layers "F.Cu" "F.Mask" "F.Paste")
			(net "GND")
		)
		(pad "D61" smd circle
			(at 21.770086 -34.379916 180)
			(size 0.450088 0.450088)
			(layers "F.Cu" "F.Mask" "F.Paste")
			(net "GND")
		)
		(pad "D62" smd circle
			(at 22.709886 -34.379916 180)
			(size 0.450088 0.450088)
			(layers "F.Cu" "F.Mask" "F.Paste")
			(net "Net_2159")
		)
		(pad "D63" smd circle
			(at 23.64994 -34.379916 180)
			(size 0.450088 0.450088)
			(layers "F.Cu" "F.Mask" "F.Paste")
			(net "GND")
		)
		(pad "D64" smd circle
			(at 24.589994 -34.379916 180)
			(size 0.450088 0.450088)
			(layers "F.Cu" "F.Mask" "F.Paste")
			(net "GND")
		)
		(pad "D65" smd circle
			(at 25.530048 -34.379916 180)
			(size 0.450088 0.450088)
			(layers "F.Cu" "F.Mask" "F.Paste")
			(net "Net_2160")
		)
		(pad "D66" smd circle
			(at 26.470102 -34.379916 180)
			(size 0.450088 0.450088)
			(layers "F.Cu" "F.Mask" "F.Paste")
			(net "GND")
		)
		(pad "D67" smd circle
			(at 27.409902 -34.379916 180)
			(size 0.450088 0.450088)
			(layers "F.Cu" "F.Mask" "F.Paste")
			(net "GND")
		)
		(pad "D68" smd circle
			(at 28.349956 -34.379916 180)
			(size 0.450088 0.450088)
			(layers "F.Cu" "F.Mask" "F.Paste")
			(net "CPU1_CORETYPE2")
		)
		(pad "D69" smd circle
			(at 29.29001 -34.379916 180)
			(size 0.450088 0.450088)
			(layers "F.Cu" "F.Mask" "F.Paste")
			(net "PWRGD_CPU1_PWROK")
		)
		(pad "D70" smd circle
			(at 30.230064 -34.379916 180)
			(size 0.450088 0.450088)
			(layers "F.Cu" "F.Mask" "F.Paste")
			(net "GND")
		)
		(pad "D71" smd circle
			(at 31.170118 -34.379916 180)
			(size 0.450088 0.450088)
			(layers "F.Cu" "F.Mask" "F.Paste")
			(net "GND")
		)
		(pad "D72" smd circle
			(at 32.109918 -34.379916 180)
			(size 0.450088 0.450088)
			(layers "F.Cu" "F.Mask" "F.Paste")
			(net "Net_2161")
		)
		(pad "D73" smd circle
			(at 33.049972 -34.379916 180)
			(size 0.450088 0.450088)
			(layers "F.Cu" "F.Mask" "F.Paste")
			(net "GND")
		)
		(pad "D74" smd circle
			(at 33.990026 -34.379916 180)
			(size 0.450088 0.450088)
			(layers "F.Cu" "F.Mask" "F.Paste")
			(net "GND")
		)
		(pad "DA1" smd circle
			(at -34.459926 30.329886 180)
			(size 0.450088 0.450088)
			(layers "F.Cu" "F.Mask" "F.Paste")
			(net "GND")
		)
		(pad "DA2" smd circle
			(at -33.519872 30.329886 180)
			(size 0.450088 0.450088)
			(layers "F.Cu" "F.Mask" "F.Paste")
			(net "M_G_CPU1_SB_DQ<26>")
		)
		(pad "DA3" smd circle
			(at -32.580072 30.329886 180)
			(size 0.450088 0.450088)
			(layers "F.Cu" "F.Mask" "F.Paste")
			(net "M_G_CPU1_SB_DQ<25>")
		)
		(pad "DA4" smd circle
			(at -31.640018 30.329886 180)
			(size 0.450088 0.450088)
			(layers "F.Cu" "F.Mask" "F.Paste")
			(net "GND")
		)
		(pad "DA5" smd circle
			(at -30.699964 30.329886 180)
			(size 0.450088 0.450088)
			(layers "F.Cu" "F.Mask" "F.Paste")
			(net "M_K_CPU1_SB_DQ<26>")
		)
		(pad "DA6" smd circle
			(at -29.75991 30.329886 180)
			(size 0.450088 0.450088)
			(layers "F.Cu" "F.Mask" "F.Paste")
			(net "GND")
		)
		(pad "DA7" smd circle
			(at -28.82011 30.329886 180)
			(size 0.450088 0.450088)
			(layers "F.Cu" "F.Mask" "F.Paste")
			(net "M_K_CPU1_SB_DQ<25>")
		)
		(pad "DA8" smd circle
			(at -27.880056 30.329886 180)
			(size 0.450088 0.450088)
			(layers "F.Cu" "F.Mask" "F.Paste")
			(net "GND")
		)
		(pad "DA9" smd circle
			(at -26.940002 30.329886 180)
			(size 0.450088 0.450088)
			(layers "F.Cu" "F.Mask" "F.Paste")
			(net "M_L_CPU1_SB_DQ<26>")
		)
		(pad "DA10" smd circle
			(at -25.999948 30.329886 180)
			(size 0.450088 0.450088)
			(layers "F.Cu" "F.Mask" "F.Paste")
			(net "M_L_CPU1_SB_DQ<25>")
		)
		(pad "DA11" smd circle
			(at -25.059894 30.329886 180)
			(size 0.450088 0.450088)
			(layers "F.Cu" "F.Mask" "F.Paste")
			(net "GND")
		)
		(pad "DA12" smd circle
			(at -24.120094 30.329886 180)
			(size 0.450088 0.450088)
			(layers "F.Cu" "F.Mask" "F.Paste")
			(net "M_H_CPU1_SB_DQ<26>")
		)
		(pad "DA13" smd circle
			(at -23.18004 30.329886 180)
			(size 0.450088 0.450088)
			(layers "F.Cu" "F.Mask" "F.Paste")
			(net "GND")
		)
		(pad "DA14" smd circle
			(at -22.239986 30.329886 180)
			(size 0.450088 0.450088)
			(layers "F.Cu" "F.Mask" "F.Paste")
			(net "M_H_CPU1_SB_DQ<25>")
		)
		(pad "DA15" smd circle
			(at -21.299932 30.329886 180)
			(size 0.450088 0.450088)
			(layers "F.Cu" "F.Mask" "F.Paste")
			(net "GND")
		)
		(pad "DA16" smd circle
			(at -20.359878 30.329886 180)
			(size 0.450088 0.450088)
			(layers "F.Cu" "F.Mask" "F.Paste")
			(net "M_J_CPU1_SB_DQ<26>")
		)
		(pad "DA17" smd circle
			(at -19.420078 30.329886 180)
			(size 0.450088 0.450088)
			(layers "F.Cu" "F.Mask" "F.Paste")
			(net "M_J_CPU1_SB_DQ<25>")
		)
		(pad "DA18" smd circle
			(at -18.480024 30.329886 180)
			(size 0.450088 0.450088)
			(layers "F.Cu" "F.Mask" "F.Paste")
			(net "GND")
		)
		(pad "DA19" smd circle
			(at -17.53997 30.329886 180)
			(size 0.450088 0.450088)
			(layers "F.Cu" "F.Mask" "F.Paste")
			(net "M_I_CPU1_SB_DQ<26>")
		)
		(pad "DA20" smd circle
			(at -16.599916 30.329886 180)
			(size 0.450088 0.450088)
			(layers "F.Cu" "F.Mask" "F.Paste")
			(net "GND")
		)
		(pad "DA21" smd circle
			(at -15.660116 30.329886 180)
			(size 0.450088 0.450088)
			(layers "F.Cu" "F.Mask" "F.Paste")
			(net "M_I_CPU1_SB_DQ<25>")
		)
	)
)
